(kicad_pcb
	(version 20260206)
	(generator "pcbnew")
	(generator_version "10.0")
	(general
		(thickness 1.6)
		(legacy_teardrops no)
	)
	(paper "A4")
	(title_block
		(title "03242023_DA0F0TMBIJ0_F0T_Motherboard_J_brd_V01_OCP.brd")
		(comment 1 "Grand Teton / footprint 885 of 6105 (J5), pads 225-291 of 291")
	)
	(layers
		(0 "F.Cu" signal "TOP")
		(4 "In1.Cu" signal "GND")
		(6 "In2.Cu" signal "IN1")
		(8 "In3.Cu" signal "GND1")
		(10 "In4.Cu" signal "IN2")
		(12 "In5.Cu" signal "GND2")
		(14 "In6.Cu" signal "IN3")
		(16 "In7.Cu" signal "GND3")
		(18 "In8.Cu" signal "VCC")
		(20 "In9.Cu" signal "VCC1")
		(22 "In10.Cu" signal "GND4")
		(24 "In11.Cu" signal "IN4")
		(26 "In12.Cu" signal "GND5")
		(28 "In13.Cu" signal "IN5")
		(30 "In14.Cu" signal "GND6")
		(32 "In15.Cu" signal "IN6")
		(34 "In16.Cu" signal "GND7")
		(2 "B.Cu" signal "BOTTOM")
		(9 "F.Adhes" user "F.Adhesive")
		(11 "B.Adhes" user "B.Adhesive")
		(13 "F.Paste" user "Package Geometry/Pastemask Top")
		(15 "B.Paste" user "Package Geometry/Pastemask Bottom")
		(5 "F.SilkS" user "Ref Des/Silkscreen Top")
		(7 "B.SilkS" user "Ref Des/Silkscreen Bottom")
		(1 "F.Mask" user "Board Geometry/Soldermask Top")
		(3 "B.Mask" user "Board Geometry/Soldermask Bottom")
		(17 "Dwgs.User" user "User.Drawings")
		(19 "Cmts.User" user "User.Comments")
		(21 "Eco1.User" user "User.Eco1")
		(23 "Eco2.User" user "User.Eco2")
		(25 "Edge.Cuts" user "Board Geometry/Outline")
		(27 "Margin" user)
		(31 "F.CrtYd" user "Package Geometry/Place Bound Top")
		(29 "B.CrtYd" user "Package Geometry/Place Bound Bottom")
		(35 "F.Fab" user "Ref Des/Assembly Top")
		(33 "B.Fab" user "Ref Des/Assembly Bottom")
	)
	(footprint ""
		(layer "F.Cu")
		(at 273.218148 -258.091686)
		(property "Reference" "J5"
			(at -3.683 -81.702148 0)
			(unlocked yes)
			(layer "F.SilkS")
			(effects
				(font
					(size 0.7874 0.5842)
					(thickness 0.1524)
				)
				(justify left)
			)
		)
		(property "Value" ""
			(at 0 0 0)
			(layer "F.Fab")
			(effects
				(font
					(size 1.27 1.27)
				)
			)
		)
		(duplicate_pad_numbers_are_jumpers no)
		(pad "225" smd rect
			(at 2.050034 9.774936 270)
			(size 0.519938 1.4986)
			(layers "F.Cu" "F.Mask" "F.Paste")
			(net "M_C_CPU0_SB_CA<5>")
		)
		(pad "226" smd rect
			(at 2.050034 10.625074 270)
			(size 0.519938 1.4986)
			(layers "F.Cu" "F.Mask" "F.Paste")
			(net "GND")
		)
		(pad "227" smd rect
			(at 2.050034 11.474958 270)
			(size 0.519938 1.4986)
			(layers "F.Cu" "F.Mask" "F.Paste")
			(net "M_C_CPU0_SB_PAR")
		)
		(pad "228" smd rect
			(at 2.050034 12.325096 270)
			(size 0.519938 1.4986)
			(layers "F.Cu" "F.Mask" "F.Paste")
			(net "GND")
		)
		(pad "229" smd rect
			(at 2.050034 13.17498 270)
			(size 0.519938 1.4986)
			(layers "F.Cu" "F.Mask" "F.Paste")
			(net "M_C_CPU0_SB_CS_N<1>")
		)
		(pad "230" smd rect
			(at 2.050034 14.025118 270)
			(size 0.519938 1.4986)
			(layers "F.Cu" "F.Mask" "F.Paste")
			(net "GND")
		)
		(pad "231" smd rect
			(at 2.050034 14.875002 270)
			(size 0.519938 1.4986)
			(layers "F.Cu" "F.Mask" "F.Paste")
			(net "TP_CHC_CPU0_DIMM1_FRU_5")
		)
		(pad "232" smd rect
			(at 2.050034 15.724886 270)
			(size 0.519938 1.4986)
			(layers "F.Cu" "F.Mask" "F.Paste")
			(net "TP_CHC_CPU0_DIMM1_FRU_6")
		)
		(pad "233" smd rect
			(at 2.050034 16.575024 270)
			(size 0.519938 1.4986)
			(layers "F.Cu" "F.Mask" "F.Paste")
			(net "GND")
		)
		(pad "234" smd rect
			(at 2.050034 17.424908 270)
			(size 0.519938 1.4986)
			(layers "F.Cu" "F.Mask" "F.Paste")
			(net "M_C_CPU0_SB_CB<6>")
		)
		(pad "235" smd rect
			(at 2.050034 18.275046 270)
			(size 0.519938 1.4986)
			(layers "F.Cu" "F.Mask" "F.Paste")
			(net "GND")
		)
		(pad "236" smd rect
			(at 2.050034 19.12493 270)
			(size 0.519938 1.4986)
			(layers "F.Cu" "F.Mask" "F.Paste")
			(net "M_C_CPU0_SB_CB<7>")
		)
		(pad "237" smd rect
			(at 2.050034 19.975068 270)
			(size 0.519938 1.4986)
			(layers "F.Cu" "F.Mask" "F.Paste")
			(net "GND")
		)
		(pad "238" smd rect
			(at 2.050034 20.824952 270)
			(size 0.519938 1.4986)
			(layers "F.Cu" "F.Mask" "F.Paste")
			(net "M_C_CPU0_SB_DQS_DN<4>")
		)
		(pad "239" smd rect
			(at 2.050034 21.67509 270)
			(size 0.519938 1.4986)
			(layers "F.Cu" "F.Mask" "F.Paste")
			(net "M_C_CPU0_SB_DQS_DP<4>")
		)
		(pad "240" smd rect
			(at 2.050034 22.524974 270)
			(size 0.519938 1.4986)
			(layers "F.Cu" "F.Mask" "F.Paste")
			(net "GND")
		)
		(pad "241" smd rect
			(at 2.050034 23.375112 270)
			(size 0.519938 1.4986)
			(layers "F.Cu" "F.Mask" "F.Paste")
			(net "M_C_CPU0_SB_CB<2>")
		)
		(pad "242" smd rect
			(at 2.050034 24.224996 270)
			(size 0.519938 1.4986)
			(layers "F.Cu" "F.Mask" "F.Paste")
			(net "GND")
		)
		(pad "243" smd rect
			(at 2.050034 25.07488 270)
			(size 0.519938 1.4986)
			(layers "F.Cu" "F.Mask" "F.Paste")
			(net "M_C_CPU0_SB_CB<3>")
		)
		(pad "244" smd rect
			(at 2.050034 25.925018 270)
			(size 0.519938 1.4986)
			(layers "F.Cu" "F.Mask" "F.Paste")
			(net "GND")
		)
		(pad "245" smd rect
			(at 2.050034 26.774902 270)
			(size 0.519938 1.4986)
			(layers "F.Cu" "F.Mask" "F.Paste")
			(net "M_C_CPU0_SB_DQ<2>")
		)
		(pad "246" smd rect
			(at 2.050034 27.62504 270)
			(size 0.519938 1.4986)
			(layers "F.Cu" "F.Mask" "F.Paste")
			(net "GND")
		)
		(pad "247" smd rect
			(at 2.050034 28.474924 270)
			(size 0.519938 1.4986)
			(layers "F.Cu" "F.Mask" "F.Paste")
			(net "M_C_CPU0_SB_DQ<3>")
		)
		(pad "248" smd rect
			(at 2.050034 29.325062 270)
			(size 0.519938 1.4986)
			(layers "F.Cu" "F.Mask" "F.Paste")
			(net "GND")
		)
		(pad "249" smd rect
			(at 2.050034 30.174946 270)
			(size 0.519938 1.4986)
			(layers "F.Cu" "F.Mask" "F.Paste")
			(net "M_C_CPU0_SB_DQS_DN<5>")
		)
		(pad "250" smd rect
			(at 2.050034 31.025084 270)
			(size 0.519938 1.4986)
			(layers "F.Cu" "F.Mask" "F.Paste")
			(net "M_C_CPU0_SB_DQS_DP<5>")
		)
		(pad "251" smd rect
			(at 2.050034 31.874968 270)
			(size 0.519938 1.4986)
			(layers "F.Cu" "F.Mask" "F.Paste")
			(net "GND")
		)
		(pad "252" smd rect
			(at 2.050034 32.725106 270)
			(size 0.519938 1.4986)
			(layers "F.Cu" "F.Mask" "F.Paste")
			(net "M_C_CPU0_SB_DQ<6>")
		)
		(pad "253" smd rect
			(at 2.050034 33.57499 270)
			(size 0.519938 1.4986)
			(layers "F.Cu" "F.Mask" "F.Paste")
			(net "GND")
		)
		(pad "254" smd rect
			(at 2.050034 34.425128 270)
			(size 0.519938 1.4986)
			(layers "F.Cu" "F.Mask" "F.Paste")
			(net "M_C_CPU0_SB_DQ<7>")
		)
		(pad "255" smd rect
			(at 2.050034 35.275012 270)
			(size 0.519938 1.4986)
			(layers "F.Cu" "F.Mask" "F.Paste")
			(net "GND")
		)
		(pad "256" smd rect
			(at 2.050034 36.124896 270)
			(size 0.519938 1.4986)
			(layers "F.Cu" "F.Mask" "F.Paste")
			(net "M_C_CPU0_SB_DQ<10>")
		)
		(pad "257" smd rect
			(at 2.050034 36.975034 270)
			(size 0.519938 1.4986)
			(layers "F.Cu" "F.Mask" "F.Paste")
			(net "GND")
		)
		(pad "258" smd rect
			(at 2.050034 37.824918 270)
			(size 0.519938 1.4986)
			(layers "F.Cu" "F.Mask" "F.Paste")
			(net "M_C_CPU0_SB_DQ<11>")
		)
		(pad "259" smd rect
			(at 2.050034 38.675056 270)
			(size 0.519938 1.4986)
			(layers "F.Cu" "F.Mask" "F.Paste")
			(net "GND")
		)
		(pad "260" smd rect
			(at 2.050034 39.52494 270)
			(size 0.519938 1.4986)
			(layers "F.Cu" "F.Mask" "F.Paste")
			(net "M_C_CPU0_SB_DQS_DN<6>")
		)
		(pad "261" smd rect
			(at 2.050034 40.375078 270)
			(size 0.519938 1.4986)
			(layers "F.Cu" "F.Mask" "F.Paste")
			(net "M_C_CPU0_SB_DQS_DP<6>")
		)
		(pad "262" smd rect
			(at 2.050034 41.224962 270)
			(size 0.519938 1.4986)
			(layers "F.Cu" "F.Mask" "F.Paste")
			(net "GND")
		)
		(pad "263" smd rect
			(at 2.050034 42.0751 270)
			(size 0.519938 1.4986)
			(layers "F.Cu" "F.Mask" "F.Paste")
			(net "M_C_CPU0_SB_DQ<14>")
		)
		(pad "264" smd rect
			(at 2.050034 42.924984 270)
			(size 0.519938 1.4986)
			(layers "F.Cu" "F.Mask" "F.Paste")
			(net "GND")
		)
		(pad "265" smd rect
			(at 2.050034 43.775122 270)
			(size 0.519938 1.4986)
			(layers "F.Cu" "F.Mask" "F.Paste")
			(net "M_C_CPU0_SB_DQ<15>")
		)
		(pad "266" smd rect
			(at 2.050034 44.625006 270)
			(size 0.519938 1.4986)
			(layers "F.Cu" "F.Mask" "F.Paste")
			(net "GND")
		)
		(pad "267" smd rect
			(at 2.050034 45.47489 270)
			(size 0.519938 1.4986)
			(layers "F.Cu" "F.Mask" "F.Paste")
			(net "M_C_CPU0_SB_DQ<18>")
		)
		(pad "268" smd rect
			(at 2.050034 46.325028 270)
			(size 0.519938 1.4986)
			(layers "F.Cu" "F.Mask" "F.Paste")
			(net "GND")
		)
		(pad "269" smd rect
			(at 2.050034 47.174912 270)
			(size 0.519938 1.4986)
			(layers "F.Cu" "F.Mask" "F.Paste")
			(net "M_C_CPU0_SB_DQ<19>")
		)
		(pad "270" smd rect
			(at 2.050034 48.02505 270)
			(size 0.519938 1.4986)
			(layers "F.Cu" "F.Mask" "F.Paste")
			(net "GND")
		)
		(pad "271" smd rect
			(at 2.050034 48.874934 270)
			(size 0.519938 1.4986)
			(layers "F.Cu" "F.Mask" "F.Paste")
			(net "M_C_CPU0_SB_DQS_DN<7>")
		)
		(pad "272" smd rect
			(at 2.050034 49.725072 270)
			(size 0.519938 1.4986)
			(layers "F.Cu" "F.Mask" "F.Paste")
			(net "M_C_CPU0_SB_DQS_DP<7>")
		)
		(pad "273" smd rect
			(at 2.050034 50.574956 270)
			(size 0.519938 1.4986)
			(layers "F.Cu" "F.Mask" "F.Paste")
			(net "GND")
		)
		(pad "274" smd rect
			(at 2.050034 51.425094 270)
			(size 0.519938 1.4986)
			(layers "F.Cu" "F.Mask" "F.Paste")
			(net "M_C_CPU0_SB_DQ<22>")
		)
		(pad "275" smd rect
			(at 2.050034 52.274978 270)
			(size 0.519938 1.4986)
			(layers "F.Cu" "F.Mask" "F.Paste")
			(net "GND")
		)
		(pad "276" smd rect
			(at 2.050034 53.125116 270)
			(size 0.519938 1.4986)
			(layers "F.Cu" "F.Mask" "F.Paste")
			(net "M_C_CPU0_SB_DQ<23>")
		)
		(pad "277" smd rect
			(at 2.050034 53.975 270)
			(size 0.519938 1.4986)
			(layers "F.Cu" "F.Mask" "F.Paste")
			(net "GND")
		)
		(pad "278" smd rect
			(at 2.050034 54.824884 270)
			(size 0.519938 1.4986)
			(layers "F.Cu" "F.Mask" "F.Paste")
			(net "M_C_CPU0_SB_DQ<26>")
		)
		(pad "279" smd rect
			(at 2.050034 55.675022 270)
			(size 0.519938 1.4986)
			(layers "F.Cu" "F.Mask" "F.Paste")
			(net "GND")
		)
		(pad "280" smd rect
			(at 2.050034 56.524906 270)
			(size 0.519938 1.4986)
			(layers "F.Cu" "F.Mask" "F.Paste")
			(net "M_C_CPU0_SB_DQ<27>")
		)
		(pad "281" smd rect
			(at 2.050034 57.375044 270)
			(size 0.519938 1.4986)
			(layers "F.Cu" "F.Mask" "F.Paste")
			(net "GND")
		)
		(pad "282" smd rect
			(at 2.050034 58.224928 270)
			(size 0.519938 1.4986)
			(layers "F.Cu" "F.Mask" "F.Paste")
			(net "M_C_CPU0_SB_DQS_DN<8>")
		)
		(pad "283" smd rect
			(at 2.050034 59.075066 270)
			(size 0.519938 1.4986)
			(layers "F.Cu" "F.Mask" "F.Paste")
			(net "M_C_CPU0_SB_DQS_DP<8>")
		)
		(pad "284" smd rect
			(at 2.050034 59.92495 270)
			(size 0.519938 1.4986)
			(layers "F.Cu" "F.Mask" "F.Paste")
			(net "GND")
		)
		(pad "285" smd rect
			(at 2.050034 60.775088 270)
			(size 0.519938 1.4986)
			(layers "F.Cu" "F.Mask" "F.Paste")
			(net "M_C_CPU0_SB_DQ<30>")
		)
		(pad "286" smd rect
			(at 2.050034 61.624972 270)
			(size 0.519938 1.4986)
			(layers "F.Cu" "F.Mask" "F.Paste")
			(net "GND")
		)
		(pad "287" smd rect
			(at 2.050034 62.47511 270)
			(size 0.519938 1.4986)
			(layers "F.Cu" "F.Mask" "F.Paste")
			(net "M_C_CPU0_SB_DQ<31>")
		)
		(pad "288" smd rect
			(at 2.050034 63.324994 270)
			(size 0.519938 1.4986)
			(layers "F.Cu" "F.Mask" "F.Paste")
			(net "GND")
		)
		(pad "G1" thru_hole oval
			(at 0 -68.97497)
			(size 2.8194 1.5748)
			(drill oval 2.4384 1.1938)
			(layers "*.Cu" "*.Mask")
			(remove_unused_layers no)
			(net "GND")
			(clearance 0.127)
			(thermal_gap 0.127)
		)
		(pad "G2" thru_hole oval
			(at 0 3.875024)
			(size 2.8194 1.5748)
			(drill oval 2.4384 1.1938)
			(layers "*.Cu" "*.Mask")
			(remove_unused_layers no)
			(net "GND")
			(clearance 0.127)
			(thermal_gap 0.127)
		)
		(pad "G3" thru_hole oval
			(at 0 68.97497)
			(size 2.8194 1.5748)
			(drill oval 2.4384 1.1938)
			(layers "*.Cu" "*.Mask")
			(remove_unused_layers no)
			(net "GND")
			(clearance 0.127)
			(thermal_gap 0.127)
		)
	)
)
